# T6G (Grand Teton) — schematic netlist excerpt (pin names and nets, part order shuffled) for the footprints in the layout excerpt that follows; sources: Cadence DE-HDL packaged netlist, KiCad conversion of 04192023_DAF0TMB3IC0_F0TG_MB_C_brd_V02_OCP.brd

C6008  Q_CAP  0.1UF 25V 10% X7R  pkg 0402  page 113 : A = P2E_MB_BMC_RX_BUF2_C_DN<0> ; B = P2E_MB_BMC_RX_BUF_DN<0>

(kicad_pcb
	(version 20260206)
	(generator "pcbnew")
	(generator_version "10.0")
	(general
		(thickness 1.6)
		(legacy_teardrops no)
	)
	(paper "A4")
	(title_block
		(title "04192023_DAF0TMB3IC0_F0TG_MB_C_brd_V02_OCP.brd")
		(comment 1 "Grand Teton / footprints 1058-1059 of 8354")
	)
	(layers
		(0 "F.Cu" signal "TOP")
		(4 "In1.Cu" signal "GND")
		(6 "In2.Cu" signal "IN1")
		(8 "In3.Cu" signal "GND1")
		(10 "In4.Cu" signal "IN2")
		(12 "In5.Cu" signal "GND2")
		(14 "In6.Cu" signal "IN3")
		(16 "In7.Cu" signal "GND3")
		(18 "In8.Cu" signal "VCC")
		(20 "In9.Cu" signal "VCC1")
		(22 "In10.Cu" signal "GND4")
		(24 "In11.Cu" signal "IN4")
		(26 "In12.Cu" signal "GND5")
		(28 "In13.Cu" signal "IN5")
		(30 "In14.Cu" signal "GND6")
		(32 "In15.Cu" signal "IN6")
		(34 "In16.Cu" signal "GND7")
		(2 "B.Cu" signal "BOTTOM")
		(9 "F.Adhes" user "F.Adhesive")
		(11 "B.Adhes" user "B.Adhesive")
		(13 "F.Paste" user "Package Geometry/Pastemask Top")
		(15 "B.Paste" user "Package Geometry/Pastemask Bottom")
		(5 "F.SilkS" user "Ref Des/Silkscreen Top")
		(7 "B.SilkS" user "Ref Des/Silkscreen Bottom")
		(1 "F.Mask" user "Board Geometry/Soldermask Top")
		(3 "B.Mask" user "Board Geometry/Soldermask Bottom")
		(17 "Dwgs.User" user "User.Drawings")
		(19 "Cmts.User" user "User.Comments")
		(21 "Eco1.User" user "User.Eco1")
		(23 "Eco2.User" user "User.Eco2")
		(25 "Edge.Cuts" user "Board Geometry/Outline")
		(27 "Margin" user)
		(31 "F.CrtYd" user "Package Geometry/Place Bound Top")
		(29 "B.CrtYd" user "Package Geometry/Place Bound Bottom")
		(35 "F.Fab" user "Ref Des/Assembly Top")
		(33 "B.Fab" user "Ref Des/Assembly Bottom")
	)
	(footprint ""
		(layer "F.Cu")
		(at 117.243352 -357.19766)
		(property "Reference" "ME17"
			(at 0 0 0)
			(layer "F.SilkS")
			(hide yes)
			(effects
				(font
					(size 1.27 1.27)
				)
			)
		)
		(property "Value" ""
			(at 0 0 0)
			(layer "F.Fab")
			(effects
				(font
					(size 1.27 1.27)
				)
			)
		)
		(duplicate_pad_numbers_are_jumpers no)
		(fp_line
			(start 0 -10.500106)
			(end 1.524 -10.500106)
			(stroke
				(width 0.1524)
				(type default)
			)
			(layer "F.SilkS")
		)
		(fp_line
			(start 0 -8.976106)
			(end 0 -10.500106)
			(stroke
				(width 0.1524)
				(type default)
			)
			(layer "F.SilkS")
		)
		(fp_line
			(start 0 0)
			(end 0 -1.524)
			(stroke
				(width 0.1524)
				(type default)
			)
			(layer "F.SilkS")
		)
		(fp_line
			(start 1.524 0)
			(end 0 0)
			(stroke
				(width 0.1524)
				(type default)
			)
			(layer "F.SilkS")
		)
		(fp_line
			(start 8.976106 0)
			(end 10.500106 0)
			(stroke
				(width 0.1524)
				(type default)
			)
			(layer "F.SilkS")
		)
		(fp_line
			(start 10.500106 -10.500106)
			(end 8.976106 -10.500106)
			(stroke
				(width 0.1524)
				(type default)
			)
			(layer "F.SilkS")
		)
		(fp_line
			(start 10.500106 -8.976106)
			(end 10.500106 -10.500106)
			(stroke
				(width 0.1524)
				(type default)
			)
			(layer "F.SilkS")
		)
		(fp_line
			(start 10.500106 0)
			(end 10.500106 -1.524)
			(stroke
				(width 0.1524)
				(type default)
			)
			(layer "F.SilkS")
		)
		(fp_text user "BIOS"
			(at 1.681226 -8.494776 0)
			(unlocked yes)
			(layer "F.SilkS")
			(effects
				(font
					(size 1.905 1.4224)
					(thickness 0.1524)
				)
				(justify left)
			)
		)
		(fp_text user "BMC"
			(at 2.303526 -1.865376 0)
			(unlocked yes)
			(layer "F.SilkS")
			(effects
				(font
					(size 1.905 1.4224)
					(thickness 0.1524)
				)
				(justify left)
			)
		)
		(fp_text user "&"
			(at 4.183126 -5.624576 0)
			(unlocked yes)
			(layer "F.SilkS")
			(effects
				(font
					(size 1.905 1.4224)
					(thickness 0.1524)
				)
				(justify left)
			)
		)
		(zone
			(layer "F.Cu")
			(hatch none 0.5)
			(connect_pads
				(clearance 0)
			)
			(min_thickness 0.25)
			(keepout
				(tracks not_allowed)
				(vias allowed)
				(pads allowed)
				(copperpour not_allowed)
				(footprints allowed)
			)
			(placement
				(enabled no)
				(sheetname "")
			)
			(fill
				(thermal_gap 0.5)
				(thermal_bridge_width 0.5)
				(island_removal_mode 0)
			)
			(polygon
				(pts
					(xy 117.243352 -357.19766) (xy 127.743458 -357.19766) (xy 127.743458 -367.697766) (xy 117.243352 -367.697766)
				)
			)
		)
	)
	(footprint ""
		(layer "F.Cu")
		(at 39.95039 -425.256706 180)
		(property "Reference" "C6008"
			(at 0 0 180)
			(layer "F.SilkS")
			(hide yes)
			(effects
				(font
					(size 1.27 1.27)
				)
			)
		)
		(property "Value" ""
			(at 0 0 180)
			(layer "F.Fab")
			(effects
				(font
					(size 1.27 1.27)
				)
			)
		)
		(duplicate_pad_numbers_are_jumpers no)
		(fp_line
			(start 0.7874 -0.4064)
			(end 0.7874 0.294894)
			(stroke
				(width 0.1524)
				(type default)
			)
			(layer "F.SilkS")
		)
		(fp_line
			(start -0.35941 0.4064)
			(end -0.7874 0.4064)
			(stroke
				(width 0.1524)
				(type default)
			)
			(layer "F.SilkS")
		)
		(fp_line
			(start -0.7874 -0.4064)
			(end 0.7874 -0.4064)
			(stroke
				(width 0.1524)
				(type default)
			)
			(layer "F.SilkS")
		)
		(fp_line
			(start 0.6858 0.3048)
			(end 0.1016 0.3048)
			(stroke
				(width 0.1)
				(type default)
			)
			(layer "F.Fab")
		)
		(fp_line
			(start 0.6858 -0.3048)
			(end 0.6858 0.3048)
			(stroke
				(width 0.1)
				(type default)
			)
			(layer "F.Fab")
		)
		(fp_line
			(start 0.1016 0.3048)
			(end 0.1016 0.2794)
			(stroke
				(width 0.1)
				(type default)
			)
			(layer "F.Fab")
		)
		(fp_line
			(start 0.1016 0.2794)
			(end -0.1016 0.2794)
			(stroke
				(width 0.1)
				(type default)
			)
			(layer "F.Fab")
		)
		(fp_line
			(start 0.1016 -0.2794)
			(end 0.1016 -0.3048)
			(stroke
				(width 0.1)
				(type default)
			)
			(layer "F.Fab")
		)
		(fp_line
			(start 0.1016 -0.3048)
			(end 0.6858 -0.3048)
			(stroke
				(width 0.1)
				(type default)
			)
			(layer "F.Fab")
		)
		(fp_line
			(start -0.1016 0.3048)
			(end -0.6858 0.3048)
			(stroke
				(width 0.1)
				(type default)
			)
			(layer "F.Fab")
		)
		(fp_line
			(start -0.1016 0.2794)
			(end -0.1016 0.3048)
			(stroke
				(width 0.1)
				(type default)
			)
			(layer "F.Fab")
		)
		(fp_line
			(start -0.1016 -0.2794)
			(end 0.1016 -0.2794)
			(stroke
				(width 0.1)
				(type default)
			)
			(layer "F.Fab")
		)
		(fp_line
			(start -0.1016 -0.3048)
			(end -0.1016 -0.2794)
			(stroke
				(width 0.1)
				(type default)
			)
			(layer "F.Fab")
		)
		(fp_line
			(start -0.6858 0.3048)
			(end -0.6858 -0.3048)
			(stroke
				(width 0.1)
				(type default)
			)
			(layer "F.Fab")
		)
		(fp_line
			(start -0.6858 -0.3048)
			(end -0.1016 -0.3048)
			(stroke
				(width 0.1)
				(type default)
			)
			(layer "F.Fab")
		)
		(pad "1" smd rect
			(at -0.40005 0)
			(size 0.4572 0.508)
			(layers "F.Cu" "F.Mask" "F.Paste")
			(net "P2E_MB_BMC_RX_BUF2_C_DN<0>")
		)
		(pad "2" smd rect
			(at 0.40005 0)
			(size 0.4572 0.508)
			(layers "F.Cu" "F.Mask" "F.Paste")
			(net "P2E_MB_BMC_RX_BUF_DN<0>")
		)
	)
)
